(kicad_pcb
	(version 20260206)
	(generator "pcbnew")
	(generator_version "10.0")
	(general
		(thickness 1.6)
		(legacy_teardrops no)
	)
	(paper "A4")
	(title_block
		(title "04192023_DAF0TMB3IC0_F0TG_MB_C_brd_V02_OCP.brd")
		(comment 1 "Grand Teton / footprints 3646-3651 of 8354")
	)
	(layers
		(0 "F.Cu" signal "TOP")
		(4 "In1.Cu" signal "GND")
		(6 "In2.Cu" signal "IN1")
		(8 "In3.Cu" signal "GND1")
		(10 "In4.Cu" signal "IN2")
		(12 "In5.Cu" signal "GND2")
		(14 "In6.Cu" signal "IN3")
		(16 "In7.Cu" signal "GND3")
		(18 "In8.Cu" signal "VCC")
		(20 "In9.Cu" signal "VCC1")
		(22 "In10.Cu" signal "GND4")
		(24 "In11.Cu" signal "IN4")
		(26 "In12.Cu" signal "GND5")
		(28 "In13.Cu" signal "IN5")
		(30 "In14.Cu" signal "GND6")
		(32 "In15.Cu" signal "IN6")
		(34 "In16.Cu" signal "GND7")
		(2 "B.Cu" signal "BOTTOM")
		(9 "F.Adhes" user "F.Adhesive")
		(11 "B.Adhes" user "B.Adhesive")
		(13 "F.Paste" user "Package Geometry/Pastemask Top")
		(15 "B.Paste" user "Package Geometry/Pastemask Bottom")
		(5 "F.SilkS" user "Ref Des/Silkscreen Top")
		(7 "B.SilkS" user "Ref Des/Silkscreen Bottom")
		(1 "F.Mask" user "Board Geometry/Soldermask Top")
		(3 "B.Mask" user "Board Geometry/Soldermask Bottom")
		(17 "Dwgs.User" user "User.Drawings")
		(19 "Cmts.User" user "User.Comments")
		(21 "Eco1.User" user "User.Eco1")
		(23 "Eco2.User" user "User.Eco2")
		(25 "Edge.Cuts" user "Board Geometry/Outline")
		(27 "Margin" user)
		(31 "F.CrtYd" user "Package Geometry/Place Bound Top")
		(29 "B.CrtYd" user "Package Geometry/Place Bound Bottom")
		(35 "F.Fab" user "Ref Des/Assembly Top")
		(33 "B.Fab" user "Ref Des/Assembly Bottom")
	)
	(footprint ""
		(layer "F.Cu")
		(at 102.154736 -119.499126 90)
		(property "Reference" "R1450"
			(at 0 0 90)
			(layer "F.SilkS")
			(hide yes)
			(effects
				(font
					(size 1.27 1.27)
				)
			)
		)
		(property "Value" ""
			(at 0 0 90)
			(layer "F.Fab")
			(effects
				(font
					(size 1.27 1.27)
				)
			)
		)
		(duplicate_pad_numbers_are_jumpers no)
		(fp_line
			(start 0.7874 -0.4064)
			(end 0.7874 0.4064)
			(stroke
				(width 0.1524)
				(type default)
			)
			(layer "F.SilkS")
		)
		(fp_line
			(start -0.7874 -0.4064)
			(end 0.7874 -0.4064)
			(stroke
				(width 0.1524)
				(type default)
			)
			(layer "F.SilkS")
		)
		(fp_line
			(start 0.7874 0.4064)
			(end -0.7874 0.4064)
			(stroke
				(width 0.1524)
				(type default)
			)
			(layer "F.SilkS")
		)
		(fp_line
			(start -0.7874 0.4064)
			(end -0.7874 -0.4064)
			(stroke
				(width 0.1524)
				(type default)
			)
			(layer "F.SilkS")
		)
		(fp_line
			(start -0.12065 -0.305054)
			(end -0.12065 -0.2794)
			(stroke
				(width 0.1)
				(type default)
			)
			(layer "F.Fab")
		)
		(fp_line
			(start -0.67945 -0.305054)
			(end -0.12065 -0.305054)
			(stroke
				(width 0.1)
				(type default)
			)
			(layer "F.Fab")
		)
		(fp_line
			(start 0.67945 -0.3048)
			(end 0.67945 0.3048)
			(stroke
				(width 0.1)
				(type default)
			)
			(layer "F.Fab")
		)
		(fp_line
			(start 0.12065 -0.3048)
			(end 0.67945 -0.3048)
			(stroke
				(width 0.1)
				(type default)
			)
			(layer "F.Fab")
		)
		(fp_line
			(start 0.12065 -0.2794)
			(end 0.12065 -0.3048)
			(stroke
				(width 0.1)
				(type default)
			)
			(layer "F.Fab")
		)
		(fp_line
			(start -0.12065 -0.2794)
			(end 0.12065 -0.2794)
			(stroke
				(width 0.1)
				(type default)
			)
			(layer "F.Fab")
		)
		(fp_line
			(start 0.120396 0.2794)
			(end -0.12065 0.2794)
			(stroke
				(width 0.1)
				(type default)
			)
			(layer "F.Fab")
		)
		(fp_line
			(start -0.12065 0.2794)
			(end -0.12065 0.3048)
			(stroke
				(width 0.1)
				(type default)
			)
			(layer "F.Fab")
		)
		(fp_line
			(start 0.67945 0.3048)
			(end 0.120396 0.3048)
			(stroke
				(width 0.1)
				(type default)
			)
			(layer "F.Fab")
		)
		(fp_line
			(start 0.120396 0.3048)
			(end 0.120396 0.2794)
			(stroke
				(width 0.1)
				(type default)
			)
			(layer "F.Fab")
		)
		(fp_line
			(start -0.12065 0.3048)
			(end -0.67945 0.3048)
			(stroke
				(width 0.1)
				(type default)
			)
			(layer "F.Fab")
		)
		(fp_line
			(start -0.67945 0.3048)
			(end -0.67945 -0.305054)
			(stroke
				(width 0.1)
				(type default)
			)
			(layer "F.Fab")
		)
		(pad "1" smd circle
			(at -0.40005 0 90)
			(size 0 0)
			(layers "F.Cu" "F.Mask" "F.Paste")
			(net "P3V3_AUX")
		)
		(pad "2" smd circle
			(at 0.40005 0 90)
			(size 0 0)
			(layers "F.Cu" "F.Mask" "F.Paste")
			(net "PWRGD_P12V_MEM_CPU0_EN_N")
		)
	)
	(footprint ""
		(layer "F.Cu")
		(at 196.457824 -65.225168 -90)
		(property "Reference" "PC2204"
			(at 0 0 270)
			(layer "F.SilkS")
			(hide yes)
			(effects
				(font
					(size 1.27 1.27)
				)
			)
		)
		(property "Value" ""
			(at 0 0 270)
			(layer "F.Fab")
			(effects
				(font
					(size 1.27 1.27)
				)
			)
		)
		(duplicate_pad_numbers_are_jumpers no)
		(fp_line
			(start -1.524 0.762)
			(end -1.524 -0.762)
			(stroke
				(width 0.1524)
				(type default)
			)
			(layer "F.SilkS")
		)
		(fp_line
			(start 1.524 0.762)
			(end -1.524 0.762)
			(stroke
				(width 0.1524)
				(type default)
			)
			(layer "F.SilkS")
		)
		(fp_line
			(start -1.524 -0.762)
			(end 1.524 -0.762)
			(stroke
				(width 0.1524)
				(type default)
			)
			(layer "F.SilkS")
		)
		(fp_line
			(start 1.524 -0.762)
			(end 1.524 0.762)
			(stroke
				(width 0.1524)
				(type default)
			)
			(layer "F.SilkS")
		)
		(fp_line
			(start -1.1049 0.724916)
			(end 1.1049 0.724916)
			(stroke
				(width 0.1)
				(type default)
			)
			(layer "F.Fab")
		)
		(fp_line
			(start 1.1049 0.724916)
			(end 1.1049 -0.724916)
			(stroke
				(width 0.1)
				(type default)
			)
			(layer "F.Fab")
		)
		(fp_line
			(start -1.1049 -0.724916)
			(end -1.1049 0.724916)
			(stroke
				(width 0.1)
				(type default)
			)
			(layer "F.Fab")
		)
		(fp_line
			(start 1.1049 -0.724916)
			(end -1.1049 -0.724916)
			(stroke
				(width 0.1)
				(type default)
			)
			(layer "F.Fab")
		)
		(pad "1" smd rect
			(at -0.889 0 90)
			(size 1.016 1.27)
			(layers "F.Cu" "F.Mask" "F.Paste")
			(net "P3V3_E1S_0_R")
		)
		(pad "2" smd rect
			(at 0.889 0 90)
			(size 1.016 1.27)
			(layers "F.Cu" "F.Mask" "F.Paste")
			(net "GND")
		)
	)
	(footprint ""
		(layer "F.Cu")
		(at 21.43887 -387.30809 90)
		(property "Reference" "PR6630"
			(at 0 0 90)
			(layer "F.SilkS")
			(hide yes)
			(effects
				(font
					(size 1.27 1.27)
				)
			)
		)
		(property "Value" ""
			(at 0 0 90)
			(layer "F.Fab")
			(effects
				(font
					(size 1.27 1.27)
				)
			)
		)
		(duplicate_pad_numbers_are_jumpers no)
		(fp_line
			(start 0.7874 -0.4064)
			(end 0.7874 0.4064)
			(stroke
				(width 0.1524)
				(type default)
			)
			(layer "F.SilkS")
		)
		(fp_line
			(start -0.7874 -0.4064)
			(end 0.7874 -0.4064)
			(stroke
				(width 0.1524)
				(type default)
			)
			(layer "F.SilkS")
		)
		(fp_line
			(start 0.7874 0.4064)
			(end -0.7874 0.4064)
			(stroke
				(width 0.1524)
				(type default)
			)
			(layer "F.SilkS")
		)
		(fp_line
			(start -0.7874 0.4064)
			(end -0.7874 -0.4064)
			(stroke
				(width 0.1524)
				(type default)
			)
			(layer "F.SilkS")
		)
		(fp_line
			(start -0.12065 -0.305054)
			(end -0.12065 -0.2794)
			(stroke
				(width 0.1)
				(type default)
			)
			(layer "F.Fab")
		)
		(fp_line
			(start -0.67945 -0.305054)
			(end -0.12065 -0.305054)
			(stroke
				(width 0.1)
				(type default)
			)
			(layer "F.Fab")
		)
		(fp_line
			(start 0.67945 -0.3048)
			(end 0.67945 0.3048)
			(stroke
				(width 0.1)
				(type default)
			)
			(layer "F.Fab")
		)
		(fp_line
			(start 0.12065 -0.3048)
			(end 0.67945 -0.3048)
			(stroke
				(width 0.1)
				(type default)
			)
			(layer "F.Fab")
		)
		(fp_line
			(start 0.12065 -0.2794)
			(end 0.12065 -0.3048)
			(stroke
				(width 0.1)
				(type default)
			)
			(layer "F.Fab")
		)
		(fp_line
			(start -0.12065 -0.2794)
			(end 0.12065 -0.2794)
			(stroke
				(width 0.1)
				(type default)
			)
			(layer "F.Fab")
		)
		(fp_line
			(start 0.120396 0.2794)
			(end -0.12065 0.2794)
			(stroke
				(width 0.1)
				(type default)
			)
			(layer "F.Fab")
		)
		(fp_line
			(start -0.12065 0.2794)
			(end -0.12065 0.3048)
			(stroke
				(width 0.1)
				(type default)
			)
			(layer "F.Fab")
		)
		(fp_line
			(start 0.67945 0.3048)
			(end 0.120396 0.3048)
			(stroke
				(width 0.1)
				(type default)
			)
			(layer "F.Fab")
		)
		(fp_line
			(start 0.120396 0.3048)
			(end 0.120396 0.2794)
			(stroke
				(width 0.1)
				(type default)
			)
			(layer "F.Fab")
		)
		(fp_line
			(start -0.12065 0.3048)
			(end -0.67945 0.3048)
			(stroke
				(width 0.1)
				(type default)
			)
			(layer "F.Fab")
		)
		(fp_line
			(start -0.67945 0.3048)
			(end -0.67945 -0.305054)
			(stroke
				(width 0.1)
				(type default)
			)
			(layer "F.Fab")
		)
		(pad "1" smd circle
			(at -0.40005 0 90)
			(size 0 0)
			(layers "F.Cu" "F.Mask" "F.Paste")
			(net "SW_P0V9_RETIMER_CPU1_SW2_RC")
		)
		(pad "2" smd circle
			(at 0.40005 0 90)
			(size 0 0)
			(layers "F.Cu" "F.Mask" "F.Paste")
			(net "GND")
		)
	)
	(footprint ""
		(layer "F.Cu")
		(at 284.461712 -351.368106 90)
		(property "Reference" "PR110"
			(at 0 0 90)
			(layer "F.SilkS")
			(hide yes)
			(effects
				(font
					(size 1.27 1.27)
				)
			)
		)
		(property "Value" ""
			(at 0 0 90)
			(layer "F.Fab")
			(effects
				(font
					(size 1.27 1.27)
				)
			)
		)
		(duplicate_pad_numbers_are_jumpers no)
		(fp_line
			(start 0.7874 -0.4064)
			(end 0.7874 0.4064)
			(stroke
				(width 0.1524)
				(type default)
			)
			(layer "F.SilkS")
		)
		(fp_line
			(start -0.7874 -0.4064)
			(end 0.7874 -0.4064)
			(stroke
				(width 0.1524)
				(type default)
			)
			(layer "F.SilkS")
		)
		(fp_line
			(start 0.7874 0.4064)
			(end -0.7874 0.4064)
			(stroke
				(width 0.1524)
				(type default)
			)
			(layer "F.SilkS")
		)
		(fp_line
			(start -0.7874 0.4064)
			(end -0.7874 -0.4064)
			(stroke
				(width 0.1524)
				(type default)
			)
			(layer "F.SilkS")
		)
		(fp_line
			(start -0.12065 -0.305054)
			(end -0.12065 -0.2794)
			(stroke
				(width 0.1)
				(type default)
			)
			(layer "F.Fab")
		)
		(fp_line
			(start -0.67945 -0.305054)
			(end -0.12065 -0.305054)
			(stroke
				(width 0.1)
				(type default)
			)
			(layer "F.Fab")
		)
		(fp_line
			(start 0.67945 -0.3048)
			(end 0.67945 0.3048)
			(stroke
				(width 0.1)
				(type default)
			)
			(layer "F.Fab")
		)
		(fp_line
			(start 0.12065 -0.3048)
			(end 0.67945 -0.3048)
			(stroke
				(width 0.1)
				(type default)
			)
			(layer "F.Fab")
		)
		(fp_line
			(start 0.12065 -0.2794)
			(end 0.12065 -0.3048)
			(stroke
				(width 0.1)
				(type default)
			)
			(layer "F.Fab")
		)
		(fp_line
			(start -0.12065 -0.2794)
			(end 0.12065 -0.2794)
			(stroke
				(width 0.1)
				(type default)
			)
			(layer "F.Fab")
		)
		(fp_line
			(start 0.120396 0.2794)
			(end -0.12065 0.2794)
			(stroke
				(width 0.1)
				(type default)
			)
			(layer "F.Fab")
		)
		(fp_line
			(start -0.12065 0.2794)
			(end -0.12065 0.3048)
			(stroke
				(width 0.1)
				(type default)
			)
			(layer "F.Fab")
		)
		(fp_line
			(start 0.67945 0.3048)
			(end 0.120396 0.3048)
			(stroke
				(width 0.1)
				(type default)
			)
			(layer "F.Fab")
		)
		(fp_line
			(start 0.120396 0.3048)
			(end 0.120396 0.2794)
			(stroke
				(width 0.1)
				(type default)
			)
			(layer "F.Fab")
		)
		(fp_line
			(start -0.12065 0.3048)
			(end -0.67945 0.3048)
			(stroke
				(width 0.1)
				(type default)
			)
			(layer "F.Fab")
		)
		(fp_line
			(start -0.67945 0.3048)
			(end -0.67945 -0.305054)
			(stroke
				(width 0.1)
				(type default)
			)
			(layer "F.Fab")
		)
		(pad "1" smd circle
			(at -0.40005 0 90)
			(size 0 0)
			(layers "F.Cu" "F.Mask" "F.Paste")
			(net "SW_PVDDIO_P0_BOOT3")
		)
		(pad "2" smd circle
			(at 0.40005 0 90)
			(size 0 0)
			(layers "F.Cu" "F.Mask" "F.Paste")
			(net "SW_PVDDIO_P0_BOOT3_R")
		)
	)
	(footprint ""
		(layer "F.Cu")
		(at 277.20798 -351.368106 -90)
		(property "Reference" "PC183"
			(at 0 0 270)
			(layer "F.SilkS")
			(hide yes)
			(effects
				(font
					(size 1.27 1.27)
				)
			)
		)
		(property "Value" ""
			(at 0 0 270)
			(layer "F.Fab")
			(effects
				(font
					(size 1.27 1.27)
				)
			)
		)
		(duplicate_pad_numbers_are_jumpers no)
		(fp_line
			(start -0.7874 0.4064)
			(end -0.7874 -0.4064)
			(stroke
				(width 0.1524)
				(type default)
			)
			(layer "F.SilkS")
		)
		(fp_line
			(start 0.7874 0.4064)
			(end -0.7874 0.4064)
			(stroke
				(width 0.1524)
				(type default)
			)
			(layer "F.SilkS")
		)
		(fp_line
			(start -0.7874 -0.4064)
			(end 0.7874 -0.4064)
			(stroke
				(width 0.1524)
				(type default)
			)
			(layer "F.SilkS")
		)
		(fp_line
			(start 0.7874 -0.4064)
			(end 0.7874 0.4064)
			(stroke
				(width 0.1524)
				(type default)
			)
			(layer "F.SilkS")
		)
		(fp_line
			(start -0.67945 0.3048)
			(end -0.67945 -0.305054)
			(stroke
				(width 0.1)
				(type default)
			)
			(layer "F.Fab")
		)
		(fp_line
			(start -0.12065 0.3048)
			(end -0.67945 0.3048)
			(stroke
				(width 0.1)
				(type default)
			)
			(layer "F.Fab")
		)
		(fp_line
			(start 0.120396 0.3048)
			(end 0.120396 0.2794)
			(stroke
				(width 0.1)
				(type default)
			)
			(layer "F.Fab")
		)
		(fp_line
			(start 0.67945 0.3048)
			(end 0.120396 0.3048)
			(stroke
				(width 0.1)
				(type default)
			)
			(layer "F.Fab")
		)
		(fp_line
			(start -0.12065 0.2794)
			(end -0.12065 0.3048)
			(stroke
				(width 0.1)
				(type default)
			)
			(layer "F.Fab")
		)
		(fp_line
			(start 0.120396 0.2794)
			(end -0.12065 0.2794)
			(stroke
				(width 0.1)
				(type default)
			)
			(layer "F.Fab")
		)
		(fp_line
			(start -0.12065 -0.2794)
			(end 0.12065 -0.2794)
			(stroke
				(width 0.1)
				(type default)
			)
			(layer "F.Fab")
		)
		(fp_line
			(start 0.12065 -0.2794)
			(end 0.12065 -0.3048)
			(stroke
				(width 0.1)
				(type default)
			)
			(layer "F.Fab")
		)
		(fp_line
			(start 0.12065 -0.3048)
			(end 0.67945 -0.3048)
			(stroke
				(width 0.1)
				(type default)
			)
			(layer "F.Fab")
		)
		(fp_line
			(start 0.67945 -0.3048)
			(end 0.67945 0.3048)
			(stroke
				(width 0.1)
				(type default)
			)
			(layer "F.Fab")
		)
		(fp_line
			(start -0.67945 -0.305054)
			(end -0.12065 -0.305054)
			(stroke
				(width 0.1)
				(type default)
			)
			(layer "F.Fab")
		)
		(fp_line
			(start -0.12065 -0.305054)
			(end -0.12065 -0.2794)
			(stroke
				(width 0.1)
				(type default)
			)
			(layer "F.Fab")
		)
		(pad "1" smd circle
			(at -0.40005 0 270)
			(size 0 0)
			(layers "F.Cu" "F.Mask" "F.Paste")
			(net "SW_PVDDIO_P0_BOOT4_R")
		)
		(pad "2" smd circle
			(at 0.40005 0 270)
			(size 0 0)
			(layers "F.Cu" "F.Mask" "F.Paste")
			(net "SW_PVDDIO_P0_BOOTR4")
		)
	)
	(footprint ""
		(layer "F.Cu")
		(at 289.314382 -351.573846 90)
		(property "Reference" "PC146_8"
			(at 0 0 90)
			(layer "F.SilkS")
			(hide yes)
			(effects
				(font
					(size 1.27 1.27)
				)
			)
		)
		(property "Value" ""
			(at 0 0 90)
			(layer "F.Fab")
			(effects
				(font
					(size 1.27 1.27)
				)
			)
		)
		(duplicate_pad_numbers_are_jumpers no)
		(fp_line
			(start 0.7874 -0.4064)
			(end 0.7874 0.4064)
			(stroke
				(width 0.1524)
				(type default)
			)
			(layer "F.SilkS")
		)
		(fp_line
			(start -0.7874 -0.4064)
			(end 0.7874 -0.4064)
			(stroke
				(width 0.1524)
				(type default)
			)
			(layer "F.SilkS")
		)
		(fp_line
			(start 0.7874 0.4064)
			(end -0.7874 0.4064)
			(stroke
				(width 0.1524)
				(type default)
			)
			(layer "F.SilkS")
		)
		(fp_line
			(start -0.7874 0.4064)
			(end -0.7874 -0.4064)
			(stroke
				(width 0.1524)
				(type default)
			)
			(layer "F.SilkS")
		)
		(fp_line
			(start -0.12065 -0.305054)
			(end -0.12065 -0.2794)
			(stroke
				(width 0.1)
				(type default)
			)
			(layer "F.Fab")
		)
		(fp_line
			(start -0.67945 -0.305054)
			(end -0.12065 -0.305054)
			(stroke
				(width 0.1)
				(type default)
			)
			(layer "F.Fab")
		)
		(fp_line
			(start 0.67945 -0.3048)
			(end 0.67945 0.3048)
			(stroke
				(width 0.1)
				(type default)
			)
			(layer "F.Fab")
		)
		(fp_line
			(start 0.12065 -0.3048)
			(end 0.67945 -0.3048)
			(stroke
				(width 0.1)
				(type default)
			)
			(layer "F.Fab")
		)
		(fp_line
			(start 0.12065 -0.2794)
			(end 0.12065 -0.3048)
			(stroke
				(width 0.1)
				(type default)
			)
			(layer "F.Fab")
		)
		(fp_line
			(start -0.12065 -0.2794)
			(end 0.12065 -0.2794)
			(stroke
				(width 0.1)
				(type default)
			)
			(layer "F.Fab")
		)
		(fp_line
			(start 0.120396 0.2794)
			(end -0.12065 0.2794)
			(stroke
				(width 0.1)
				(type default)
			)
			(layer "F.Fab")
		)
		(fp_line
			(start -0.12065 0.2794)
			(end -0.12065 0.3048)
			(stroke
				(width 0.1)
				(type default)
			)
			(layer "F.Fab")
		)
		(fp_line
			(start 0.67945 0.3048)
			(end 0.120396 0.3048)
			(stroke
				(width 0.1)
				(type default)
			)
			(layer "F.Fab")
		)
		(fp_line
			(start 0.120396 0.3048)
			(end 0.120396 0.2794)
			(stroke
				(width 0.1)
				(type default)
			)
			(layer "F.Fab")
		)
		(fp_line
			(start -0.12065 0.3048)
			(end -0.67945 0.3048)
			(stroke
				(width 0.1)
				(type default)
			)
			(layer "F.Fab")
		)
		(fp_line
			(start -0.67945 0.3048)
			(end -0.67945 -0.305054)
			(stroke
				(width 0.1)
				(type default)
			)
			(layer "F.Fab")
		)
		(pad "1" smd circle
			(at -0.40005 0 90)
			(size 0 0)
			(layers "F.Cu" "F.Mask" "F.Paste")
			(net "PVDDCR_CPU1_P0_VCCS")
		)
		(pad "2" smd circle
			(at 0.40005 0 90)
			(size 0 0)
			(layers "F.Cu" "F.Mask" "F.Paste")
			(net "GND")
		)
	)
)
